(kicad_pcb
	(version 20241229)
	(generator "pcbnew")
	(generator_version "9.0")
	(general
		(thickness 1.294)
		(legacy_teardrops no)
	)
	(paper "A3")
	(title_block
		(title "Kintex 410T devboard")
		(date "2024-04-03")
		(rev "1.1.2")
		(comment 9 "footprints 14-19 of 975")
	)
	(layers
		(0 "F.Cu" mixed)
		(4 "In1.Cu" power)
		(6 "In2.Cu" power)
		(8 "In3.Cu" mixed)
		(10 "In4.Cu" power)
		(12 "In5.Cu" mixed)
		(14 "In6.Cu" power)
		(16 "In7.Cu" mixed)
		(18 "In8.Cu" power)
		(2 "B.Cu" mixed)
		(9 "F.Adhes" user "F.Adhesive")
		(11 "B.Adhes" user "B.Adhesive")
		(13 "F.Paste" user)
		(15 "B.Paste" user)
		(5 "F.SilkS" user "F.Silkscreen")
		(7 "B.SilkS" user "B.Silkscreen")
		(1 "F.Mask" user)
		(3 "B.Mask" user)
		(17 "Dwgs.User" user "User.Drawings")
		(19 "Cmts.User" user "User.Comments")
		(21 "Eco1.User" user "User.Eco1")
		(23 "Eco2.User" user "User.Eco2")
		(25 "Edge.Cuts" user)
		(27 "Margin" user)
		(31 "F.CrtYd" user "F.Courtyard")
		(29 "B.CrtYd" user "B.Courtyard")
		(35 "F.Fab" user)
		(33 "B.Fab" user)
	)
	(footprint "antmicro-footprints:Resonator_SMD_Abracon_ABM8G_3.2x2.5mm"
		(layer "F.Cu")
		(at 204.853752 102.8365 180)
		(property "Reference" "Y4"
			(at -5.346248 -8.0635 0)
			(layer "F.SilkS")
			(effects
				(font
					(size 0.7 0.7)
					(thickness 0.15)
				)
				(justify left bottom)
			)
		)
		(property "Value" "Resonator_25MHz_ABM8G"
			(at -1.75 2.548 180)
			(layer "F.Fab")
			(effects
				(font
					(size 0.7 0.7)
					(thickness 0.15)
				)
				(justify left bottom)
			)
		)
		(property "Description" "Crystal, 25 MHz, SMD, 3.2mm x 2.5mm, 30 ppm, 18 pF, 20 ppm, ABM8G"
			(at 0 0 180)
			(layer "F.Fab")
			(hide yes)
			(effects
				(font
					(size 1.27 1.27)
					(thickness 0.15)
				)
			)
		)
		(property "Author" "Antmicro"
			(at 409.707504 205.673 0)
			(layer "F.Fab")
			(hide yes)
			(effects
				(font
					(size 1 1)
					(thickness 0.15)
				)
			)
		)
		(property "License" "Apache-2.0"
			(at 409.707504 205.673 0)
			(layer "F.Fab")
			(hide yes)
			(effects
				(font
					(size 1 1)
					(thickness 0.15)
				)
			)
		)
		(property "MPN" "ABM8G-25.000MHZ-18-D2Y-T3"
			(at 409.707504 205.673 0)
			(layer "F.Fab")
			(hide yes)
			(effects
				(font
					(size 1 1)
					(thickness 0.15)
				)
			)
		)
		(property "Manufacturer" "Abracon"
			(at 409.707504 205.673 0)
			(layer "F.Fab")
			(hide yes)
			(effects
				(font
					(size 1 1)
					(thickness 0.15)
				)
			)
		)
		(property "Val" "25 MHz"
			(at 409.707504 205.673 0)
			(layer "F.Fab")
			(hide yes)
			(effects
				(font
					(size 1 1)
					(thickness 0.15)
				)
			)
		)
		(sheetname "HDMI + Ethernet")
		(sheetfile "hdmi-ethernet.kicad_sch")
		(attr smd)
		(fp_line
			(start 1.6 0.3)
			(end 1.6 -0.2)
			(stroke
				(width 0.15)
				(type solid)
			)
			(layer "F.SilkS")
		)
		(fp_line
			(start -0.35 1.25)
			(end 0.45 1.25)
			(stroke
				(width 0.15)
				(type solid)
			)
			(layer "F.SilkS")
		)
		(fp_line
			(start -0.35 -1.25)
			(end 0.45 -1.25)
			(stroke
				(width 0.15)
				(type solid)
			)
			(layer "F.SilkS")
		)
		(fp_line
			(start -1.6 0.3)
			(end -1.6 -0.2)
			(stroke
				(width 0.15)
				(type solid)
			)
			(layer "F.SilkS")
		)
		(fp_circle
			(center -1.75 1.5)
			(end -1.7 1.5)
			(stroke
				(width 0.15)
				(type solid)
			)
			(fill no)
			(layer "F.SilkS")
		)
		(fp_rect
			(start -1.907 -1.55)
			(end 2.006 1.649)
			(stroke
				(width 0.05)
				(type solid)
			)
			(fill no)
			(layer "F.CrtYd")
		)
		(pad "1" smd roundrect
			(at -1.101 0.949 180)
			(size 1.3 1.1)
			(layers "F.Cu" "F.Mask" "F.Paste")
			(roundrect_rratio 0)
			(chamfer_ratio 0.2)
			(chamfer bottom_left)
			(net 718 "/HDMI + Ethernet/GBE_XI")
			(pintype "passive")
		)
		(pad "2" smd rect
			(at 1.199 0.949 180)
			(size 1.3 1.1)
			(layers "F.Cu" "F.Mask" "F.Paste")
			(net 1 "GND")
			(pinfunction "SH")
			(pintype "passive")
		)
		(pad "3" smd rect
			(at 1.199 -0.85 180)
			(size 1.3 1.1)
			(layers "F.Cu" "F.Mask" "F.Paste")
			(net 720 "/HDMI + Ethernet/GBE_XO")
			(pintype "passive")
		)
		(pad "4" smd rect
			(at -1.101 -0.85 180)
			(size 1.3 1.1)
			(layers "F.Cu" "F.Mask" "F.Paste")
			(net 1 "GND")
			(pinfunction "SH")
			(pintype "passive")
		)
	)
	(footprint "antmicro-footprints:R_0603_1608Metric"
		(layer "F.Cu")
		(at 151.4 141 -90)
		(descr "Resistor SMD 0603")
		(tags "resistor SMD 0603")
		(property "Reference" "R326"
			(at 2.39 -1.44 270)
			(layer "F.SilkS")
			(effects
				(font
					(size 0.7 0.7)
					(thickness 0.15)
				)
				(justify left bottom)
			)
		)
		(property "Value" "R_0R_22.4A_0603"
			(at 0 1.6 270)
			(layer "F.Fab")
			(effects
				(font
					(size 0.7 0.7)
					(thickness 0.15)
				)
				(justify left bottom)
			)
		)
		(property "Description" "SMD Chip Resistor"
			(at 0 0 270)
			(layer "F.Fab")
			(hide yes)
			(effects
				(font
					(size 1.27 1.27)
					(thickness 0.15)
				)
			)
		)
		(property "Author" "Antmicro"
			(at 10.4 292.4 0)
			(layer "F.Fab")
			(hide yes)
			(effects
				(font
					(size 1 1)
					(thickness 0.15)
				)
			)
		)
		(property "License" "Apache-2.0"
			(at 10.4 292.4 0)
			(layer "F.Fab")
			(hide yes)
			(effects
				(font
					(size 1 1)
					(thickness 0.15)
				)
			)
		)
		(property "MPN" "PMR03EZPJ000"
			(at 10.4 292.4 0)
			(layer "F.Fab")
			(hide yes)
			(effects
				(font
					(size 1 1)
					(thickness 0.15)
				)
			)
		)
		(property "Manufacturer" "ROHM Semiconductor"
			(at 10.4 292.4 0)
			(layer "F.Fab")
			(hide yes)
			(effects
				(font
					(size 1 1)
					(thickness 0.15)
				)
			)
		)
		(property "Max. Curr." "22.4A"
			(at 10.4 292.4 0)
			(layer "F.Fab")
			(hide yes)
			(effects
				(font
					(size 1 1)
					(thickness 0.15)
				)
			)
		)
		(property "Tolerance" "template_tolerance"
			(at 10.4 292.4 0)
			(layer "F.Fab")
			(hide yes)
			(effects
				(font
					(size 1 1)
					(thickness 0.15)
				)
			)
		)
		(property "Val" "0R"
			(at 10.4 292.4 0)
			(layer "F.Fab")
			(hide yes)
			(effects
				(font
					(size 1 1)
					(thickness 0.15)
				)
			)
		)
		(sheetname "DC-DC Converters")
		(sheetfile "dc-dc.kicad_sch")
		(attr smd)
		(fp_line
			(start -0.15 0.4)
			(end 0.15 0.4)
			(stroke
				(width 0.15)
				(type solid)
			)
			(layer "F.SilkS")
		)
		(fp_line
			(start -0.15 -0.4)
			(end 0.15 -0.4)
			(stroke
				(width 0.15)
				(type solid)
			)
			(layer "F.SilkS")
		)
		(fp_rect
			(start -1.25 -0.65)
			(end 1.25 0.65)
			(stroke
				(width 0.05)
				(type solid)
			)
			(fill no)
			(layer "F.CrtYd")
		)
		(fp_rect
			(start -0.8 -0.4)
			(end 0.8 0.4)
			(stroke
				(width 0.15)
				(type solid)
			)
			(fill no)
			(layer "F.Fab")
		)
		(pad "1" smd roundrect
			(at -0.7 0 270)
			(size 0.8 1)
			(layers "F.Cu" "F.Mask" "F.Paste")
			(roundrect_rratio 0.2)
			(net 748 "/DC-DC Converters/MGTAVTT_OUT")
			(pintype "passive")
		)
		(pad "2" smd roundrect
			(at 0.7 0 270)
			(size 0.8 1)
			(layers "F.Cu" "F.Mask" "F.Paste")
			(roundrect_rratio 0.2)
			(net 8 "+1V2_MGTAVTT")
			(pintype "passive")
		)
	)
	(footprint "antmicro-footprints:R_0402_1005Metric"
		(layer "F.Cu")
		(at 244.999 113.904)
		(descr "Resistor SMD 0402")
		(tags "resistor SMD 0402")
		(property "Reference" "R350"
			(at -1.299 -0.504 0)
			(layer "F.SilkS")
			(effects
				(font
					(size 0.7 0.7)
					(thickness 0.15)
				)
				(justify left bottom)
			)
		)
		(property "Value" "R_10k_0402"
			(at 0 1.4 0)
			(layer "F.Fab")
			(effects
				(font
					(size 0.7 0.7)
					(thickness 0.15)
				)
				(justify left bottom)
			)
		)
		(property "Description" "SMD Chip Resistor, 10 kohm, ± 1%, 62.5 mW, 0402 [1005 Metric], Thick Film, General Purpose"
			(at 0 0 0)
			(layer "F.Fab")
			(hide yes)
			(effects
				(font
					(size 1.27 1.27)
					(thickness 0.15)
				)
			)
		)
		(property "Author" "Antmicro"
			(at 0 0 0)
			(layer "F.Fab")
			(hide yes)
			(effects
				(font
					(size 1 1)
					(thickness 0.15)
				)
			)
		)
		(property "License" "Apache-2.0"
			(at 0 0 0)
			(layer "F.Fab")
			(hide yes)
			(effects
				(font
					(size 1 1)
					(thickness 0.15)
				)
			)
		)
		(property "MPN" "CR0402-FX-1002GLF"
			(at 0 0 0)
			(layer "F.Fab")
			(hide yes)
			(effects
				(font
					(size 1 1)
					(thickness 0.15)
				)
			)
		)
		(property "Manufacturer" "Bourns"
			(at 0 0 0)
			(layer "F.Fab")
			(hide yes)
			(effects
				(font
					(size 1 1)
					(thickness 0.15)
				)
			)
		)
		(property "Tolerance" "1%"
			(at 0 0 0)
			(layer "F.Fab")
			(hide yes)
			(effects
				(font
					(size 1 1)
					(thickness 0.15)
				)
			)
		)
		(property "Val" "10k"
			(at 0 0 0)
			(layer "F.Fab")
			(hide yes)
			(effects
				(font
					(size 1 1)
					(thickness 0.15)
				)
			)
		)
		(sheetname "USB PHY")
		(sheetfile "usb-phy.kicad_sch")
		(attr smd)
		(fp_rect
			(start -0.925 -0.47)
			(end 0.925 0.47)
			(stroke
				(width 0.05)
				(type default)
			)
			(fill no)
			(layer "F.CrtYd")
		)
		(fp_rect
			(start -0.5 -0.25)
			(end 0.5 0.25)
			(stroke
				(width 0.15)
				(type solid)
			)
			(fill no)
			(layer "F.Fab")
		)
		(pad "1" smd roundrect
			(at -0.48 0)
			(size 0.59 0.64)
			(layers "F.Cu" "F.Mask" "F.Paste")
			(roundrect_rratio 0.25)
			(net 385 "Net-(U43-EN)")
			(pintype "passive")
		)
		(pad "2" smd roundrect
			(at 0.48 0)
			(size 0.59 0.64)
			(layers "F.Cu" "F.Mask" "F.Paste")
			(roundrect_rratio 0.25)
			(net 1 "GND")
			(pintype "passive")
		)
	)
	(footprint "antmicro-footprints:C_0402_1005Metric"
		(layer "F.Cu")
		(at 157.7 147.9)
		(descr "Capacitor SMD 0402")
		(tags "capacitor SMD 0402")
		(property "Reference" "C362"
			(at -1.9 1.25 0)
			(layer "F.SilkS")
			(effects
				(font
					(size 0.7 0.7)
					(thickness 0.15)
				)
				(justify left bottom)
			)
		)
		(property "Value" "C_100n_0402"
			(at 0 1.4 0)
			(layer "F.Fab")
			(effects
				(font
					(size 0.7 0.7)
					(thickness 0.15)
				)
				(justify left bottom)
			)
		)
		(property "Description" "SMD Multilayer Ceramic Capacitor, 0.1 µF, 50 V, 0402 [1005 Metric], ± 10%, X5R, GRM Series"
			(at 0 0 0)
			(layer "F.Fab")
			(hide yes)
			(effects
				(font
					(size 1.27 1.27)
					(thickness 0.15)
				)
			)
		)
		(property "Author" "Antmicro"
			(at 0 0 0)
			(layer "F.Fab")
			(hide yes)
			(effects
				(font
					(size 1 1)
					(thickness 0.15)
				)
			)
		)
		(property "Dielectric" "X5R"
			(at 0 0 0)
			(layer "F.Fab")
			(hide yes)
			(effects
				(font
					(size 1 1)
					(thickness 0.15)
				)
			)
		)
		(property "License" "Apache-2.0"
			(at 0 0 0)
			(layer "F.Fab")
			(hide yes)
			(effects
				(font
					(size 1 1)
					(thickness 0.15)
				)
			)
		)
		(property "MPN" "GRM155R61H104KE14D"
			(at 0 0 0)
			(layer "F.Fab")
			(hide yes)
			(effects
				(font
					(size 1 1)
					(thickness 0.15)
				)
			)
		)
		(property "Manufacturer" "Murata"
			(at 0 0 0)
			(layer "F.Fab")
			(hide yes)
			(effects
				(font
					(size 1 1)
					(thickness 0.15)
				)
			)
		)
		(property "Val" "100n"
			(at 0 0 0)
			(layer "F.Fab")
			(hide yes)
			(effects
				(font
					(size 1 1)
					(thickness 0.15)
				)
			)
		)
		(property "Voltage" "50V"
			(at 0 0 0)
			(layer "F.Fab")
			(hide yes)
			(effects
				(font
					(size 1 1)
					(thickness 0.15)
				)
			)
		)
		(sheetname "DC-DC Converters")
		(sheetfile "dc-dc.kicad_sch")
		(attr smd)
		(fp_rect
			(start -0.925 -0.47)
			(end 0.925 0.47)
			(stroke
				(width 0.05)
				(type default)
			)
			(fill no)
			(layer "F.CrtYd")
		)
		(fp_line
			(start -0.494 -0.25)
			(end 0.504 -0.25)
			(stroke
				(width 0.15)
				(type solid)
			)
			(layer "F.Fab")
		)
		(fp_line
			(start -0.494 0.248)
			(end -0.494 -0.25)
			(stroke
				(width 0.15)
				(type solid)
			)
			(layer "F.Fab")
		)
		(fp_line
			(start 0.504 -0.25)
			(end 0.504 0.248)
			(stroke
				(width 0.15)
				(type solid)
			)
			(layer "F.Fab")
		)
		(fp_line
			(start 0.504 0.248)
			(end -0.494 0.248)
			(stroke
				(width 0.15)
				(type solid)
			)
			(layer "F.Fab")
		)
		(pad "1" smd roundrect
			(at -0.48 0)
			(size 0.59 0.64)
			(layers "F.Cu" "F.Mask" "F.Paste")
			(roundrect_rratio 0.25)
			(net 1 "GND")
			(pintype "passive")
		)
		(pad "2" smd roundrect
			(at 0.48 0)
			(size 0.59 0.64)
			(layers "F.Cu" "F.Mask" "F.Paste")
			(roundrect_rratio 0.25)
			(net 15 "Net-(U41-OUT)")
			(pintype "passive")
		)
	)
	(footprint "antmicro-footprints:USON-10_2.5x1mm_P0.5mm"
		(layer "F.Cu")
		(at 261.7 146 180)
		(descr "USON-10 2.5x1mm_ Pitch 0.5mm")
		(tags "USON-10 2.5x1mm Pitch 0.5mm")
		(property "Reference" "U17"
			(at 1.1 -2.4 180)
			(layer "F.SilkS")
			(effects
				(font
					(size 0.7 0.7)
					(thickness 0.15)
				)
				(justify left bottom)
			)
		)
		(property "Value" "TPD4E05U06QDQARQ1"
			(at 0.018 2.499 180)
			(layer "F.Fab")
			(effects
				(font
					(size 0.7 0.7)
					(thickness 0.15)
				)
				(justify left bottom)
			)
		)
		(property "Description" "ESD protection"
			(at 0 0 180)
			(layer "F.Fab")
			(hide yes)
			(effects
				(font
					(size 1.27 1.27)
					(thickness 0.15)
				)
			)
		)
		(property "Author" "Antmicro"
			(at 523.4 292 0)
			(layer "F.Fab")
			(hide yes)
			(effects
				(font
					(size 1 1)
					(thickness 0.15)
				)
			)
		)
		(property "License" "Apache-2.0"
			(at 523.4 292 0)
			(layer "F.Fab")
			(hide yes)
			(effects
				(font
					(size 1 1)
					(thickness 0.15)
				)
			)
		)
		(property "MPN" "TPD4E05U06QDQARQ1"
			(at 523.4 292 0)
			(layer "F.Fab")
			(hide yes)
			(effects
				(font
					(size 1 1)
					(thickness 0.15)
				)
			)
		)
		(property "Manufacturer" "Texas Instruments"
			(at 523.4 292 0)
			(layer "F.Fab")
			(hide yes)
			(effects
				(font
					(size 1 1)
					(thickness 0.15)
				)
			)
		)
		(sheetname "USB PHY")
		(sheetfile "usb-phy.kicad_sch")
		(attr smd)
		(fp_line
			(start 0.498 1.398)
			(end -0.5 1.398)
			(stroke
				(width 0.15)
				(type solid)
			)
			(layer "F.SilkS")
		)
		(fp_line
			(start 0.498 -1.401)
			(end -0.5 -1.401)
			(stroke
				(width 0.15)
				(type solid)
			)
			(layer "F.SilkS")
		)
		(fp_circle
			(center -0.68 -1.27)
			(end -0.63 -1.27)
			(stroke
				(width 0.15)
				(type solid)
			)
			(fill yes)
			(layer "F.SilkS")
		)
		(fp_rect
			(start -0.8 -1.5)
			(end 0.8 1.499)
			(stroke
				(width 0.05)
				(type solid)
			)
			(fill no)
			(layer "F.CrtYd")
		)
		(fp_line
			(start 0.498 -1.25)
			(end 0.498 1.249)
			(stroke
				(width 0.15)
				(type solid)
			)
			(layer "F.Fab")
		)
		(fp_line
			(start 0.498 -1.25)
			(end -0.25 -1.25)
			(stroke
				(width 0.15)
				(type solid)
			)
			(layer "F.Fab")
		)
		(fp_line
			(start -0.25 -1.25)
			(end -0.5 -1)
			(stroke
				(width 0.15)
				(type solid)
			)
			(layer "F.Fab")
		)
		(fp_line
			(start -0.5 1.249)
			(end 0.498 1.249)
			(stroke
				(width 0.15)
				(type solid)
			)
			(layer "F.Fab")
		)
		(fp_line
			(start -0.5 -1)
			(end -0.5 1.249)
			(stroke
				(width 0.15)
				(type solid)
			)
			(layer "F.Fab")
		)
		(pad "1" smd roundrect
			(at -0.387 -1 90)
			(size 0.25 0.55)
			(layers "F.Cu" "F.Mask" "F.Paste")
			(roundrect_rratio 0.25)
			(net 837 "/Power supply/USB_DBG_PD.CC1")
			(pintype "passive")
		)
		(pad "2" smd roundrect
			(at -0.387 -0.5 90)
			(size 0.25 0.55)
			(layers "F.Cu" "F.Mask" "F.Paste")
			(roundrect_rratio 0.25)
			(net 838 "/USB PHY/USB_DBG_CONN_D+")
			(pintype "passive")
		)
		(pad "3" smd roundrect
			(at -0.387 0 90)
			(size 0.4 0.55)
			(layers "F.Cu" "F.Mask" "F.Paste")
			(roundrect_rratio 0.25)
			(net 1 "GND")
			(pintype "power_in")
		)
		(pad "4" smd roundrect
			(at -0.387 0.498 90)
			(size 0.25 0.55)
			(layers "F.Cu" "F.Mask" "F.Paste")
			(roundrect_rratio 0.25)
			(net 839 "/USB PHY/USB_DBG_CONN_D-")
			(pintype "passive")
		)
		(pad "5" smd roundrect
			(at -0.387 0.998 90)
			(size 0.25 0.55)
			(layers "F.Cu" "F.Mask" "F.Paste")
			(roundrect_rratio 0.25)
			(net 840 "/Power supply/USB_DBG_PD.CC2")
			(pintype "passive")
		)
		(pad "6" smd roundrect
			(at 0.385 0.998 90)
			(size 0.25 0.55)
			(layers "F.Cu" "F.Mask" "F.Paste")
			(roundrect_rratio 0.25)
			(net 840 "/Power supply/USB_DBG_PD.CC2")
			(pintype "passive")
		)
		(pad "7" smd roundrect
			(at 0.385 0.498 90)
			(size 0.25 0.55)
			(layers "F.Cu" "F.Mask" "F.Paste")
			(roundrect_rratio 0.25)
			(net 839 "/USB PHY/USB_DBG_CONN_D-")
			(pintype "passive")
		)
		(pad "8" smd roundrect
			(at 0.385 0 90)
			(size 0.4 0.55)
			(layers "F.Cu" "F.Mask" "F.Paste")
			(roundrect_rratio 0.25)
			(net 1 "GND")
			(pintype "passive")
		)
		(pad "9" smd roundrect
			(at 0.385 -0.5 90)
			(size 0.25 0.55)
			(layers "F.Cu" "F.Mask" "F.Paste")
			(roundrect_rratio 0.25)
			(net 838 "/USB PHY/USB_DBG_CONN_D+")
			(pintype "passive")
		)
		(pad "10" smd roundrect
			(at 0.385 -1 90)
			(size 0.25 0.55)
			(layers "F.Cu" "F.Mask" "F.Paste")
			(roundrect_rratio 0.25)
			(net 837 "/Power supply/USB_DBG_PD.CC1")
			(pintype "passive")
		)
	)
	(footprint "antmicro-footprints:R_0402_1005Metric"
		(layer "F.Cu")
		(at 171.25 169.3125 90)
		(descr "Resistor SMD 0402")
		(tags "resistor SMD 0402")
		(property "Reference" "R300"
			(at -1.4375 -0.5 90)
			(layer "F.SilkS")
			(effects
				(font
					(size 0.7 0.7)
					(thickness 0.15)
				)
				(justify left bottom)
			)
		)
		(property "Value" "R_0R_0402"
			(at 0 1.4 90)
			(layer "F.Fab")
			(effects
				(font
					(size 0.7 0.7)
					(thickness 0.15)
				)
				(justify left bottom)
			)
		)
		(property "Description" "SMD Chip Resistor, Jumper, 0 ohm, 100 mW, 0402 [1005 Metric], Thick Film, General Purpose"
			(at 0 0 90)
			(layer "F.Fab")
			(hide yes)
			(effects
				(font
					(size 1.27 1.27)
					(thickness 0.15)
				)
			)
		)
		(property "Author" "Antmicro"
			(at 340.5625 -1.9375 0)
			(layer "F.Fab")
			(hide yes)
			(effects
				(font
					(size 1 1)
					(thickness 0.15)
				)
			)
		)
		(property "Current" "1A"
			(at 340.5625 -1.9375 0)
			(layer "F.Fab")
			(hide yes)
			(effects
				(font
					(size 1 1)
					(thickness 0.15)
				)
			)
		)
		(property "License" "Apache-2.0"
			(at 340.5625 -1.9375 0)
			(layer "F.Fab")
			(hide yes)
			(effects
				(font
					(size 1 1)
					(thickness 0.15)
				)
			)
		)
		(property "MPN" "ERJ2GE0R00X"
			(at 340.5625 -1.9375 0)
			(layer "F.Fab")
			(hide yes)
			(effects
				(font
					(size 1 1)
					(thickness 0.15)
				)
			)
		)
		(property "Manufacturer" "Panasonic"
			(at 340.5625 -1.9375 0)
			(layer "F.Fab")
			(hide yes)
			(effects
				(font
					(size 1 1)
					(thickness 0.15)
				)
			)
		)
		(property "Tolerance" ""
			(at 340.5625 -1.9375 0)
			(layer "F.Fab")
			(hide yes)
			(effects
				(font
					(size 1 1)
					(thickness 0.15)
				)
			)
		)
		(property "Val" "0R"
			(at 340.5625 -1.9375 0)
			(layer "F.Fab")
			(hide yes)
			(effects
				(font
					(size 1 1)
					(thickness 0.15)
				)
			)
		)
		(sheetname "DC-DC Converters")
		(sheetfile "dc-dc.kicad_sch")
		(attr smd)
		(fp_rect
			(start -0.925 -0.47)
			(end 0.925 0.47)
			(stroke
				(width 0.05)
				(type default)
			)
			(fill no)
			(layer "F.CrtYd")
		)
		(fp_rect
			(start -0.5 -0.25)
			(end 0.5 0.25)
			(stroke
				(width 0.15)
				(type solid)
			)
			(fill no)
			(layer "F.Fab")
		)
		(pad "1" smd roundrect
			(at -0.48 0 90)
			(size 0.59 0.64)
			(layers "F.Cu" "F.Mask" "F.Paste")
			(roundrect_rratio 0.25)
			(net 958 "/DC-DC Converters/FB5")
			(pintype "passive")
		)
		(pad "2" smd roundrect
			(at 0.48 0 90)
			(size 0.59 0.64)
			(layers "F.Cu" "F.Mask" "F.Paste")
			(roundrect_rratio 0.25)
			(net 735 "/DC-DC Converters/3V3_local")
			(pintype "passive")
		)
	)
)
